(kicad_pcb
	(version 20260206)
	(generator "pcbnew")
	(generator_version "10.0")
	(general
		(thickness 1.6)
		(legacy_teardrops no)
	)
	(paper "A4")
	(title_block
		(title "04192023_DAF0TMB3IC0_F0TG_MB_C_brd_V02_OCP.brd")
		(comment 1 "Grand Teton / footprints 4106-4111 of 8354")
	)
	(layers
		(0 "F.Cu" signal "TOP")
		(4 "In1.Cu" signal "GND")
		(6 "In2.Cu" signal "IN1")
		(8 "In3.Cu" signal "GND1")
		(10 "In4.Cu" signal "IN2")
		(12 "In5.Cu" signal "GND2")
		(14 "In6.Cu" signal "IN3")
		(16 "In7.Cu" signal "GND3")
		(18 "In8.Cu" signal "VCC")
		(20 "In9.Cu" signal "VCC1")
		(22 "In10.Cu" signal "GND4")
		(24 "In11.Cu" signal "IN4")
		(26 "In12.Cu" signal "GND5")
		(28 "In13.Cu" signal "IN5")
		(30 "In14.Cu" signal "GND6")
		(32 "In15.Cu" signal "IN6")
		(34 "In16.Cu" signal "GND7")
		(2 "B.Cu" signal "BOTTOM")
		(9 "F.Adhes" user "F.Adhesive")
		(11 "B.Adhes" user "B.Adhesive")
		(13 "F.Paste" user "Package Geometry/Pastemask Top")
		(15 "B.Paste" user "Package Geometry/Pastemask Bottom")
		(5 "F.SilkS" user "Ref Des/Silkscreen Top")
		(7 "B.SilkS" user "Ref Des/Silkscreen Bottom")
		(1 "F.Mask" user "Board Geometry/Soldermask Top")
		(3 "B.Mask" user "Board Geometry/Soldermask Bottom")
		(17 "Dwgs.User" user "User.Drawings")
		(19 "Cmts.User" user "User.Comments")
		(21 "Eco1.User" user "User.Eco1")
		(23 "Eco2.User" user "User.Eco2")
		(25 "Edge.Cuts" user "Board Geometry/Outline")
		(27 "Margin" user)
		(31 "F.CrtYd" user "Package Geometry/Place Bound Top")
		(29 "B.CrtYd" user "Package Geometry/Place Bound Bottom")
		(35 "F.Fab" user "Ref Des/Assembly Top")
		(33 "B.Fab" user "Ref Des/Assembly Bottom")
	)
	(footprint ""
		(layer "F.Cu")
		(at 244.327426 -283.853636)
		(property "Reference" "PC6502"
			(at 0 0 0)
			(layer "F.SilkS")
			(hide yes)
			(effects
				(font
					(size 1.27 1.27)
				)
			)
		)
		(property "Value" ""
			(at 0 0 0)
			(layer "F.Fab")
			(effects
				(font
					(size 1.27 1.27)
				)
			)
		)
		(duplicate_pad_numbers_are_jumpers no)
		(fp_line
			(start -1.524 -0.762)
			(end 1.524 -0.762)
			(stroke
				(width 0.1524)
				(type default)
			)
			(layer "F.SilkS")
		)
		(fp_line
			(start -1.524 0.762)
			(end -1.524 -0.762)
			(stroke
				(width 0.1524)
				(type default)
			)
			(layer "F.SilkS")
		)
		(fp_line
			(start 1.524 -0.762)
			(end 1.524 0.762)
			(stroke
				(width 0.1524)
				(type default)
			)
			(layer "F.SilkS")
		)
		(fp_line
			(start 1.524 0.762)
			(end -1.524 0.762)
			(stroke
				(width 0.1524)
				(type default)
			)
			(layer "F.SilkS")
		)
		(fp_line
			(start -1.1049 -0.724916)
			(end -1.1049 0.724916)
			(stroke
				(width 0.1)
				(type default)
			)
			(layer "F.Fab")
		)
		(fp_line
			(start -1.1049 0.724916)
			(end 1.1049 0.724916)
			(stroke
				(width 0.1)
				(type default)
			)
			(layer "F.Fab")
		)
		(fp_line
			(start 1.1049 -0.724916)
			(end -1.1049 -0.724916)
			(stroke
				(width 0.1)
				(type default)
			)
			(layer "F.Fab")
		)
		(fp_line
			(start 1.1049 0.724916)
			(end 1.1049 -0.724916)
			(stroke
				(width 0.1)
				(type default)
			)
			(layer "F.Fab")
		)
		(pad "1" smd rect
			(at -0.889 0 180)
			(size 1.016 1.27)
			(layers "F.Cu" "F.Mask" "F.Paste")
			(net "SW_P12V_AUX_P1V8_RETIMER_CPU0_FLT")
		)
		(pad "2" smd rect
			(at 0.889 0 180)
			(size 1.016 1.27)
			(layers "F.Cu" "F.Mask" "F.Paste")
			(net "GND")
		)
	)
	(footprint ""
		(layer "F.Cu")
		(at 384.113278 -140.202158 180)
		(property "Reference" "PR290"
			(at 0 0 180)
			(layer "F.SilkS")
			(hide yes)
			(effects
				(font
					(size 1.27 1.27)
				)
			)
		)
		(property "Value" ""
			(at 0 0 180)
			(layer "F.Fab")
			(effects
				(font
					(size 1.27 1.27)
				)
			)
		)
		(duplicate_pad_numbers_are_jumpers no)
		(fp_line
			(start 0.7874 0.4064)
			(end -0.7874 0.4064)
			(stroke
				(width 0.1524)
				(type default)
			)
			(layer "F.SilkS")
		)
		(fp_line
			(start 0.7874 -0.4064)
			(end 0.7874 0.4064)
			(stroke
				(width 0.1524)
				(type default)
			)
			(layer "F.SilkS")
		)
		(fp_line
			(start -0.7874 0.4064)
			(end -0.7874 -0.4064)
			(stroke
				(width 0.1524)
				(type default)
			)
			(layer "F.SilkS")
		)
		(fp_line
			(start -0.7874 -0.4064)
			(end 0.7874 -0.4064)
			(stroke
				(width 0.1524)
				(type default)
			)
			(layer "F.SilkS")
		)
		(fp_line
			(start 0.67945 0.3048)
			(end 0.120396 0.3048)
			(stroke
				(width 0.1)
				(type default)
			)
			(layer "F.Fab")
		)
		(fp_line
			(start 0.67945 -0.3048)
			(end 0.67945 0.3048)
			(stroke
				(width 0.1)
				(type default)
			)
			(layer "F.Fab")
		)
		(fp_line
			(start 0.12065 -0.2794)
			(end 0.12065 -0.3048)
			(stroke
				(width 0.1)
				(type default)
			)
			(layer "F.Fab")
		)
		(fp_line
			(start 0.12065 -0.3048)
			(end 0.67945 -0.3048)
			(stroke
				(width 0.1)
				(type default)
			)
			(layer "F.Fab")
		)
		(fp_line
			(start 0.120396 0.3048)
			(end 0.120396 0.2794)
			(stroke
				(width 0.1)
				(type default)
			)
			(layer "F.Fab")
		)
		(fp_line
			(start 0.120396 0.2794)
			(end -0.12065 0.2794)
			(stroke
				(width 0.1)
				(type default)
			)
			(layer "F.Fab")
		)
		(fp_line
			(start -0.12065 0.3048)
			(end -0.67945 0.3048)
			(stroke
				(width 0.1)
				(type default)
			)
			(layer "F.Fab")
		)
		(fp_line
			(start -0.12065 0.2794)
			(end -0.12065 0.3048)
			(stroke
				(width 0.1)
				(type default)
			)
			(layer "F.Fab")
		)
		(fp_line
			(start -0.12065 -0.2794)
			(end 0.12065 -0.2794)
			(stroke
				(width 0.1)
				(type default)
			)
			(layer "F.Fab")
		)
		(fp_line
			(start -0.12065 -0.305054)
			(end -0.12065 -0.2794)
			(stroke
				(width 0.1)
				(type default)
			)
			(layer "F.Fab")
		)
		(fp_line
			(start -0.67945 0.3048)
			(end -0.67945 -0.305054)
			(stroke
				(width 0.1)
				(type default)
			)
			(layer "F.Fab")
		)
		(fp_line
			(start -0.67945 -0.305054)
			(end -0.12065 -0.305054)
			(stroke
				(width 0.1)
				(type default)
			)
			(layer "F.Fab")
		)
		(pad "1" smd circle
			(at -0.40005 0 180)
			(size 0 0)
			(layers "F.Cu" "F.Mask" "F.Paste")
			(net "P5V_AUX")
		)
		(pad "2" smd circle
			(at 0.40005 0 180)
			(size 0 0)
			(layers "F.Cu" "F.Mask" "F.Paste")
			(net "PVDDCR_CPU0_P0_VMON")
		)
	)
	(footprint ""
		(layer "F.Cu")
		(at 22.987254 -35.8013 180)
		(property "Reference" "R1274"
			(at 0 0 180)
			(layer "F.SilkS")
			(hide yes)
			(effects
				(font
					(size 1.27 1.27)
				)
			)
		)
		(property "Value" ""
			(at 0 0 180)
			(layer "F.Fab")
			(effects
				(font
					(size 1.27 1.27)
				)
			)
		)
		(duplicate_pad_numbers_are_jumpers no)
		(fp_line
			(start 0.7874 0.4064)
			(end -0.7874 0.4064)
			(stroke
				(width 0.1524)
				(type default)
			)
			(layer "F.SilkS")
		)
		(fp_line
			(start 0.7874 -0.4064)
			(end 0.7874 0.4064)
			(stroke
				(width 0.1524)
				(type default)
			)
			(layer "F.SilkS")
		)
		(fp_line
			(start -0.7874 0.4064)
			(end -0.7874 -0.4064)
			(stroke
				(width 0.1524)
				(type default)
			)
			(layer "F.SilkS")
		)
		(fp_line
			(start -0.7874 -0.4064)
			(end 0.7874 -0.4064)
			(stroke
				(width 0.1524)
				(type default)
			)
			(layer "F.SilkS")
		)
		(fp_line
			(start 0.67945 0.3048)
			(end 0.120396 0.3048)
			(stroke
				(width 0.1)
				(type default)
			)
			(layer "F.Fab")
		)
		(fp_line
			(start 0.67945 -0.3048)
			(end 0.67945 0.3048)
			(stroke
				(width 0.1)
				(type default)
			)
			(layer "F.Fab")
		)
		(fp_line
			(start 0.12065 -0.2794)
			(end 0.12065 -0.3048)
			(stroke
				(width 0.1)
				(type default)
			)
			(layer "F.Fab")
		)
		(fp_line
			(start 0.12065 -0.3048)
			(end 0.67945 -0.3048)
			(stroke
				(width 0.1)
				(type default)
			)
			(layer "F.Fab")
		)
		(fp_line
			(start 0.120396 0.3048)
			(end 0.120396 0.2794)
			(stroke
				(width 0.1)
				(type default)
			)
			(layer "F.Fab")
		)
		(fp_line
			(start 0.120396 0.2794)
			(end -0.12065 0.2794)
			(stroke
				(width 0.1)
				(type default)
			)
			(layer "F.Fab")
		)
		(fp_line
			(start -0.12065 0.3048)
			(end -0.67945 0.3048)
			(stroke
				(width 0.1)
				(type default)
			)
			(layer "F.Fab")
		)
		(fp_line
			(start -0.12065 0.2794)
			(end -0.12065 0.3048)
			(stroke
				(width 0.1)
				(type default)
			)
			(layer "F.Fab")
		)
		(fp_line
			(start -0.12065 -0.2794)
			(end 0.12065 -0.2794)
			(stroke
				(width 0.1)
				(type default)
			)
			(layer "F.Fab")
		)
		(fp_line
			(start -0.12065 -0.305054)
			(end -0.12065 -0.2794)
			(stroke
				(width 0.1)
				(type default)
			)
			(layer "F.Fab")
		)
		(fp_line
			(start -0.67945 0.3048)
			(end -0.67945 -0.305054)
			(stroke
				(width 0.1)
				(type default)
			)
			(layer "F.Fab")
		)
		(fp_line
			(start -0.67945 -0.305054)
			(end -0.12065 -0.305054)
			(stroke
				(width 0.1)
				(type default)
			)
			(layer "F.Fab")
		)
		(pad "1" smd circle
			(at -0.40005 0 180)
			(size 0 0)
			(layers "F.Cu" "F.Mask" "F.Paste")
			(net "SMB_INA230_7_3V3AUX_SCL_R")
		)
		(pad "2" smd circle
			(at 0.40005 0 180)
			(size 0 0)
			(layers "F.Cu" "F.Mask" "F.Paste")
			(net "SMB_INA230_7_3V3AUX_SCL_R1")
		)
	)
	(footprint ""
		(layer "F.Cu")
		(at 53.53431 -337.403948)
		(property "Reference" "PL47"
			(at -3.115056 -15.887446 0)
			(unlocked yes)
			(layer "F.SilkS")
			(effects
				(font
					(size 0.7874 0.5842)
					(thickness 0.1524)
				)
				(justify left)
			)
		)
		(property "Value" ""
			(at 0 0 0)
			(layer "F.Fab")
			(effects
				(font
					(size 1.27 1.27)
				)
			)
		)
		(duplicate_pad_numbers_are_jumpers no)
		(fp_line
			(start -3.750056 -5.500116)
			(end -2.393442 -5.500116)
			(stroke
				(width 0.1524)
				(type default)
			)
			(layer "F.SilkS")
		)
		(fp_line
			(start -3.750056 5.500116)
			(end -3.750056 -5.500116)
			(stroke
				(width 0.1524)
				(type default)
			)
			(layer "F.SilkS")
		)
		(fp_line
			(start -2.393442 5.500116)
			(end -3.750056 5.500116)
			(stroke
				(width 0.1524)
				(type default)
			)
			(layer "F.SilkS")
		)
		(fp_line
			(start 2.393442 5.500116)
			(end 3.750056 5.500116)
			(stroke
				(width 0.1524)
				(type default)
			)
			(layer "F.SilkS")
		)
		(fp_line
			(start 3.750056 -5.500116)
			(end 2.393442 -5.500116)
			(stroke
				(width 0.1524)
				(type default)
			)
			(layer "F.SilkS")
		)
		(fp_line
			(start 3.750056 5.500116)
			(end 3.750056 -5.500116)
			(stroke
				(width 0.1524)
				(type default)
			)
			(layer "F.SilkS")
		)
		(fp_poly
			(pts
				(xy -3.9116 -4.249928) (xy -4.3434 -4.034028) (xy -4.3434 -4.465828)
			)
			(stroke
				(width 0)
				(type default)
			)
			(fill yes)
			(layer "F.SilkS")
		)
		(fp_line
			(start -3.750056 -5.500116)
			(end -3.750056 5.500116)
			(stroke
				(width 0.1)
				(type default)
			)
			(layer "F.Fab")
		)
		(fp_line
			(start -3.750056 5.500116)
			(end 3.750056 5.500116)
			(stroke
				(width 0.1)
				(type default)
			)
			(layer "F.Fab")
		)
		(fp_line
			(start 3.750056 -5.500116)
			(end -3.750056 -5.500116)
			(stroke
				(width 0.1)
				(type default)
			)
			(layer "F.Fab")
		)
		(fp_line
			(start 3.750056 5.500116)
			(end 3.750056 -5.500116)
			(stroke
				(width 0.1)
				(type default)
			)
			(layer "F.Fab")
		)
		(fp_poly
			(pts
				(xy -4.9276 -4.757928) (xy -4.9276 -3.741928) (xy -3.9116 -4.249928)
			)
			(stroke
				(width 0)
				(type default)
			)
			(fill yes)
			(layer "F.Fab")
		)
		(pad "1" smd rect
			(at 0 -4.249928 270)
			(size 2.413 4.5212)
			(layers "F.Cu" "F.Mask" "F.Paste")
			(net "SW_PVDDIO_P1_SW1")
		)
		(pad "2" smd rect
			(at 0 -1.175004 270)
			(size 1.3716 4.5212)
			(layers "F.Cu" "F.Mask" "F.Paste")
			(net "IND_PVDDIO_P1_CPL2")
		)
		(pad "3" smd rect
			(at 0 1.175004 270)
			(size 1.3716 4.5212)
			(layers "F.Cu" "F.Mask" "F.Paste")
			(net "GND")
		)
		(pad "4" smd rect
			(at 0 4.249928 270)
			(size 2.413 4.5212)
			(layers "F.Cu" "F.Mask" "F.Paste")
			(net "PVDDIO_P1")
		)
	)
	(footprint ""
		(layer "F.Cu")
		(at 177.45583 -157.508194 -90)
		(property "Reference" "R498"
			(at 0 0 270)
			(layer "F.SilkS")
			(hide yes)
			(effects
				(font
					(size 1.27 1.27)
				)
			)
		)
		(property "Value" ""
			(at 0 0 270)
			(layer "F.Fab")
			(effects
				(font
					(size 1.27 1.27)
				)
			)
		)
		(duplicate_pad_numbers_are_jumpers no)
		(fp_line
			(start -0.7874 0.4064)
			(end -0.7874 -0.4064)
			(stroke
				(width 0.1524)
				(type default)
			)
			(layer "F.SilkS")
		)
		(fp_line
			(start 0.7874 0.4064)
			(end -0.7874 0.4064)
			(stroke
				(width 0.1524)
				(type default)
			)
			(layer "F.SilkS")
		)
		(fp_line
			(start -0.7874 -0.4064)
			(end 0.7874 -0.4064)
			(stroke
				(width 0.1524)
				(type default)
			)
			(layer "F.SilkS")
		)
		(fp_line
			(start 0.7874 -0.4064)
			(end 0.7874 0.4064)
			(stroke
				(width 0.1524)
				(type default)
			)
			(layer "F.SilkS")
		)
		(fp_line
			(start -0.67945 0.3048)
			(end -0.67945 -0.305054)
			(stroke
				(width 0.1)
				(type default)
			)
			(layer "F.Fab")
		)
		(fp_line
			(start -0.12065 0.3048)
			(end -0.67945 0.3048)
			(stroke
				(width 0.1)
				(type default)
			)
			(layer "F.Fab")
		)
		(fp_line
			(start 0.120396 0.3048)
			(end 0.120396 0.2794)
			(stroke
				(width 0.1)
				(type default)
			)
			(layer "F.Fab")
		)
		(fp_line
			(start 0.67945 0.3048)
			(end 0.120396 0.3048)
			(stroke
				(width 0.1)
				(type default)
			)
			(layer "F.Fab")
		)
		(fp_line
			(start -0.12065 0.2794)
			(end -0.12065 0.3048)
			(stroke
				(width 0.1)
				(type default)
			)
			(layer "F.Fab")
		)
		(fp_line
			(start 0.120396 0.2794)
			(end -0.12065 0.2794)
			(stroke
				(width 0.1)
				(type default)
			)
			(layer "F.Fab")
		)
		(fp_line
			(start -0.12065 -0.2794)
			(end 0.12065 -0.2794)
			(stroke
				(width 0.1)
				(type default)
			)
			(layer "F.Fab")
		)
		(fp_line
			(start 0.12065 -0.2794)
			(end 0.12065 -0.3048)
			(stroke
				(width 0.1)
				(type default)
			)
			(layer "F.Fab")
		)
		(fp_line
			(start 0.12065 -0.3048)
			(end 0.67945 -0.3048)
			(stroke
				(width 0.1)
				(type default)
			)
			(layer "F.Fab")
		)
		(fp_line
			(start 0.67945 -0.3048)
			(end 0.67945 0.3048)
			(stroke
				(width 0.1)
				(type default)
			)
			(layer "F.Fab")
		)
		(fp_line
			(start -0.67945 -0.305054)
			(end -0.12065 -0.305054)
			(stroke
				(width 0.1)
				(type default)
			)
			(layer "F.Fab")
		)
		(fp_line
			(start -0.12065 -0.305054)
			(end -0.12065 -0.2794)
			(stroke
				(width 0.1)
				(type default)
			)
			(layer "F.Fab")
		)
		(pad "1" smd circle
			(at -0.40005 0 270)
			(size 0 0)
			(layers "F.Cu" "F.Mask" "F.Paste")
			(net "PVDD18_S5_P0")
		)
		(pad "2" smd circle
			(at 0.40005 0 270)
			(size 0 0)
			(layers "F.Cu" "F.Mask" "F.Paste")
			(net "SMB_CPU0_4_SDA")
		)
	)
	(footprint ""
		(layer "F.Cu")
		(at 276.181312 -351.368106 90)
		(property "Reference" "PR109"
			(at 0 0 90)
			(layer "F.SilkS")
			(hide yes)
			(effects
				(font
					(size 1.27 1.27)
				)
			)
		)
		(property "Value" ""
			(at 0 0 90)
			(layer "F.Fab")
			(effects
				(font
					(size 1.27 1.27)
				)
			)
		)
		(duplicate_pad_numbers_are_jumpers no)
		(fp_line
			(start 0.7874 -0.4064)
			(end 0.7874 0.4064)
			(stroke
				(width 0.1524)
				(type default)
			)
			(layer "F.SilkS")
		)
		(fp_line
			(start -0.7874 -0.4064)
			(end 0.7874 -0.4064)
			(stroke
				(width 0.1524)
				(type default)
			)
			(layer "F.SilkS")
		)
		(fp_line
			(start 0.7874 0.4064)
			(end -0.7874 0.4064)
			(stroke
				(width 0.1524)
				(type default)
			)
			(layer "F.SilkS")
		)
		(fp_line
			(start -0.7874 0.4064)
			(end -0.7874 -0.4064)
			(stroke
				(width 0.1524)
				(type default)
			)
			(layer "F.SilkS")
		)
		(fp_line
			(start -0.12065 -0.305054)
			(end -0.12065 -0.2794)
			(stroke
				(width 0.1)
				(type default)
			)
			(layer "F.Fab")
		)
		(fp_line
			(start -0.67945 -0.305054)
			(end -0.12065 -0.305054)
			(stroke
				(width 0.1)
				(type default)
			)
			(layer "F.Fab")
		)
		(fp_line
			(start 0.67945 -0.3048)
			(end 0.67945 0.3048)
			(stroke
				(width 0.1)
				(type default)
			)
			(layer "F.Fab")
		)
		(fp_line
			(start 0.12065 -0.3048)
			(end 0.67945 -0.3048)
			(stroke
				(width 0.1)
				(type default)
			)
			(layer "F.Fab")
		)
		(fp_line
			(start 0.12065 -0.2794)
			(end 0.12065 -0.3048)
			(stroke
				(width 0.1)
				(type default)
			)
			(layer "F.Fab")
		)
		(fp_line
			(start -0.12065 -0.2794)
			(end 0.12065 -0.2794)
			(stroke
				(width 0.1)
				(type default)
			)
			(layer "F.Fab")
		)
		(fp_line
			(start 0.120396 0.2794)
			(end -0.12065 0.2794)
			(stroke
				(width 0.1)
				(type default)
			)
			(layer "F.Fab")
		)
		(fp_line
			(start -0.12065 0.2794)
			(end -0.12065 0.3048)
			(stroke
				(width 0.1)
				(type default)
			)
			(layer "F.Fab")
		)
		(fp_line
			(start 0.67945 0.3048)
			(end 0.120396 0.3048)
			(stroke
				(width 0.1)
				(type default)
			)
			(layer "F.Fab")
		)
		(fp_line
			(start 0.120396 0.3048)
			(end 0.120396 0.2794)
			(stroke
				(width 0.1)
				(type default)
			)
			(layer "F.Fab")
		)
		(fp_line
			(start -0.12065 0.3048)
			(end -0.67945 0.3048)
			(stroke
				(width 0.1)
				(type default)
			)
			(layer "F.Fab")
		)
		(fp_line
			(start -0.67945 0.3048)
			(end -0.67945 -0.305054)
			(stroke
				(width 0.1)
				(type default)
			)
			(layer "F.Fab")
		)
		(pad "1" smd circle
			(at -0.40005 0 90)
			(size 0 0)
			(layers "F.Cu" "F.Mask" "F.Paste")
			(net "SW_PVDDIO_P0_BOOT4")
		)
		(pad "2" smd circle
			(at 0.40005 0 90)
			(size 0 0)
			(layers "F.Cu" "F.Mask" "F.Paste")
			(net "SW_PVDDIO_P0_BOOT4_R")
		)
	)
)
